# T6G (Grand Teton) — schematic netlist excerpt (pin names and nets, part order shuffled) for the footprints in the layout excerpt that follows; sources: Cadence DE-HDL packaged netlist, KiCad conversion of 04192023_DAF0TMB3IC0_F0TG_MB_C_brd_V02_OCP.brd

J112  CONN160_10131762101LF  CONN160_10131762-101LF IO  pkg HSD_F160D8_P2W1-2_RDH  page 122
  A1  = RST_PERST_2_SWB_BUF_N
  A2  = GND
  A3  = HGX_DETECT_N_ISO
  A4  = GND
  A5  = RST_PERST_1_SWB_BUF_N
  A6  = GND
  A7  = PRSNT_SWB_N
  A8  = GND
  B1  = GND
  B2  = P5E_CPU1_P0_RX_BUF_DN<1>
  B3  = GND
  B4  = P5E_CPU1_P0_RX_BUF_DN<3>
  B5  = GND
  B6  = P5E_CPU1_P0_RX_BUF_DN<5>
  B7  = GND
  B8  = P5E_CPU1_P0_RX_BUF_DN<7>
  C1  = P5E_CPU1_P0_RX_BUF_DN<0>
  C2  = P5E_CPU1_P0_RX_BUF_DP<1>
  C3  = P5E_CPU1_P0_RX_BUF_DN<2>
  C4  = P5E_CPU1_P0_RX_BUF_DP<3>
  C5  = P5E_CPU1_P0_RX_BUF_DN<4>
  C6  = P5E_CPU1_P0_RX_BUF_DP<5>
  C7  = P5E_CPU1_P0_RX_BUF_DN<6>
  C8  = P5E_CPU1_P0_RX_BUF_DP<7>
  D1  = P5E_CPU1_P0_RX_BUF_DP<0>
  D2  = GND
  D3  = P5E_CPU1_P0_RX_BUF_DP<2>
  D4  = GND
  D5  = P5E_CPU1_P0_RX_BUF_DP<4>
  D6  = GND
  D7  = P5E_CPU1_P0_RX_BUF_DP<6>
  D8  = GND
  E1  = GND
  E2  = P5E_CPU1_P1_RX_BUF_DN<1>
  E3  = GND
  E4  = P5E_CPU1_P1_RX_BUF_DN<3>
  E5  = GND
  E6  = P5E_CPU1_P1_RX_BUF_DN<5>
  E7  = GND
  E8  = P5E_CPU1_P1_RX_BUF_DN<7>
  F1  = P5E_CPU1_P1_RX_BUF_DN<0>
  F2  = P5E_CPU1_P1_RX_BUF_DP<1>
  F3  = P5E_CPU1_P1_RX_BUF_DN<2>
  F4  = P5E_CPU1_P1_RX_BUF_DP<3>
  F5  = P5E_CPU1_P1_RX_BUF_DN<4>
  F6  = P5E_CPU1_P1_RX_BUF_DP<5>
  F7  = P5E_CPU1_P1_RX_BUF_DN<6>
  F8  = P5E_CPU1_P1_RX_BUF_DP<7>
  G1  = P5E_CPU1_P1_RX_BUF_DP<0>
  G2  = GND
  G3  = P5E_CPU1_P1_RX_BUF_DP<2>
  G4  = GND
  G5  = P5E_CPU1_P1_RX_BUF_DP<4>
  G6  = GND
  G7  = P5E_CPU1_P1_RX_BUF_DP<6>
  G8  = GND
  H1  = GND
  H2  = P5E_CPU1_P0_TX_BUF_C_DN<1>
  H3  = GND
  H4  = P5E_CPU1_P0_TX_BUF_C_DN<3>
  H5  = GND
  H6  = P5E_CPU1_P0_TX_BUF_C_DN<5>
  H7  = GND
  H8  = P5E_CPU1_P0_TX_BUF_C_DN<7>
  I1  = P5E_CPU1_P0_TX_BUF_C_DN<0>
  I2  = P5E_CPU1_P0_TX_BUF_C_DP<1>
  I3  = P5E_CPU1_P0_TX_BUF_C_DN<2>
  I4  = P5E_CPU1_P0_TX_BUF_C_DP<3>
  I5  = P5E_CPU1_P0_TX_BUF_C_DN<4>
  I6  = P5E_CPU1_P0_TX_BUF_C_DP<5>
  I7  = P5E_CPU1_P0_TX_BUF_C_DN<6>
  I8  = P5E_CPU1_P0_TX_BUF_C_DP<7>
  J1  = P5E_CPU1_P0_TX_BUF_C_DP<0>
  J2  = GND
  J3  = P5E_CPU1_P0_TX_BUF_C_DP<2>
  J4  = GND
  J5  = P5E_CPU1_P0_TX_BUF_C_DP<4>
  J6  = GND
  J7  = P5E_CPU1_P0_TX_BUF_C_DP<6>
  J8  = GND
  K1  = GND
  K2  = P5E_CPU1_P1_TX_BUF_C_DN<1>
  K3  = GND
  K4  = P5E_CPU1_P1_TX_BUF_C_DN<3>
  K5  = GND
  K6  = P5E_CPU1_P1_TX_BUF_C_DN<5>
  K7  = GND
  K8  = P5E_CPU1_P1_TX_BUF_C_DN<7>
  L1  = P5E_CPU1_P1_TX_BUF_C_DN<0>
  L2  = P5E_CPU1_P1_TX_BUF_C_DP<1>
  L3  = P5E_CPU1_P1_TX_BUF_C_DN<2>
  L4  = P5E_CPU1_P1_TX_BUF_C_DP<3>
  L5  = P5E_CPU1_P1_TX_BUF_C_DN<4>
  L6  = P5E_CPU1_P1_TX_BUF_C_DP<5>
  L7  = P5E_CPU1_P1_TX_BUF_C_DN<6>
  L8  = P5E_CPU1_P1_TX_BUF_C_DP<7>
  M1  = P5E_CPU1_P1_TX_BUF_C_DP<0>
  M2  = GND
  M3  = P5E_CPU1_P1_TX_BUF_C_DP<2>
  M4  = GND
  M5  = P5E_CPU1_P1_TX_BUF_C_DP<4>
  M6  = GND
  M7  = P5E_CPU1_P1_TX_BUF_C_DP<6>
  M8  = GND
  N1  = GND
  N2  = NC_J112_N2
  N3  = GND
  N4  = CLK_100M_CPU0_CLK11_DN
  N5  = GND
  N6  = P2E_MB_BMC_RX_DP<0>
  N7  = GND
  N8  = P3E_CPU1_P5_RX_DN<0>
  O1  = CLK_100M_CPU1_CLK01_DN
  O2  = NC_J112_O2
  O3  = CLK_100M_CPU1_CLK11_DN
  O4  = CLK_100M_CPU0_CLK11_DP
  O5  = NC_J112_O5
  O6  = P2E_MB_BMC_RX_DN<0>
  O7  = P3E_CPU1_P5_RX_DN<1>
  O8  = P3E_CPU1_P5_RX_DP<0>
  P1  = CLK_100M_CPU1_CLK01_DP
  P2  = GND
  P3  = CLK_100M_CPU1_CLK11_DP
  P4  = GND
  P5  = NC_J112_P5
  P6  = GND
  P7  = P3E_CPU1_P5_RX_DP<1>
  P8  = GND
  Q1  = GND
  Q2  = CLK_100M_GPU_FPGA_DN
  Q3  = GND
  Q4  = SMB_1_BMC_GPU_BUF_SCL
  Q5  = GND
  Q6  = P2E_MB_BMC_TX_BUF_C_DP<0>
  Q7  = GND
  Q8  = P3E_CPU1_P5_TX_C_DN<0>
  R1  = USB2_HUB_BUF_SWB_DN
  R2  = CLK_100M_GPU_FPGA_DP
  R3  = SMB_2_BMC_GPU_BUF_SCL
  R4  = SMB_1_BMC_GPU_BUF_SDA
  R5  = NC_J112_R5
  R6  = P2E_MB_BMC_TX_BUF_C_DN<0>
  R7  = P3E_CPU1_P5_TX_C_DP<1>
  R8  = P3E_CPU1_P5_TX_C_DP<0>
  S1  = USB2_HUB_BUF_SWB_DP
  S2  = GND
  S3  = SMB_2_BMC_GPU_BUF_SDA
  S4  = GND
  S5  = NC_J112_S5
  S6  = GND
  S7  = P3E_CPU1_P5_TX_C_DN<1>
  S8  = GND
  T1  = GND
  T2  = GPU_FPGA_READY
  T3  = GND
  T4  = GPU_NVS_PWR_BRAKE_N_BUF
  T5  = GND
  T6  = GPU_FPGA_THERM_OVERT_N
  T7  = GND
  T8  = RST_PERST_0_SWB_BUF_N

(kicad_pcb
	(version 20260206)
	(generator "pcbnew")
	(generator_version "10.0")
	(general
		(thickness 1.6)
		(legacy_teardrops no)
	)
	(paper "A4")
	(title_block
		(title "04192023_DAF0TMB3IC0_F0TG_MB_C_brd_V02_OCP.brd")
		(comment 1 "Grand Teton / footprint 625 of 8354 (J112), pads 32-62 of 74")
	)
	(layers
		(0 "F.Cu" signal "TOP")
		(4 "In1.Cu" signal "GND")
		(6 "In2.Cu" signal "IN1")
		(8 "In3.Cu" signal "GND1")
		(10 "In4.Cu" signal "IN2")
		(12 "In5.Cu" signal "GND2")
		(14 "In6.Cu" signal "IN3")
		(16 "In7.Cu" signal "GND3")
		(18 "In8.Cu" signal "VCC")
		(20 "In9.Cu" signal "VCC1")
		(22 "In10.Cu" signal "GND4")
		(24 "In11.Cu" signal "IN4")
		(26 "In12.Cu" signal "GND5")
		(28 "In13.Cu" signal "IN5")
		(30 "In14.Cu" signal "GND6")
		(32 "In15.Cu" signal "IN6")
		(34 "In16.Cu" signal "GND7")
		(2 "B.Cu" signal "BOTTOM")
		(9 "F.Adhes" user "F.Adhesive")
		(11 "B.Adhes" user "B.Adhesive")
		(13 "F.Paste" user "Package Geometry/Pastemask Top")
		(15 "B.Paste" user "Package Geometry/Pastemask Bottom")
		(5 "F.SilkS" user "Ref Des/Silkscreen Top")
		(7 "B.SilkS" user "Ref Des/Silkscreen Bottom")
		(1 "F.Mask" user "Board Geometry/Soldermask Top")
		(3 "B.Mask" user "Board Geometry/Soldermask Bottom")
		(17 "Dwgs.User" user "User.Drawings")
		(19 "Cmts.User" user "User.Comments")
		(21 "Eco1.User" user "User.Eco1")
		(23 "Eco2.User" user "User.Eco2")
		(25 "Edge.Cuts" user "Board Geometry/Outline")
		(27 "Margin" user)
		(31 "F.CrtYd" user "Package Geometry/Place Bound Top")
		(29 "B.CrtYd" user "Package Geometry/Place Bound Bottom")
		(35 "F.Fab" user "Ref Des/Assembly Top")
		(33 "B.Fab" user "Ref Des/Assembly Bottom")
	)
	(footprint ""
		(layer "F.Cu")
		(at 58.64987 -440.489848)
		(property "Reference" "J112"
			(at -4.958842 26.716736 90)
			(unlocked yes)
			(layer "F.SilkS")
			(effects
				(font
					(size 0.7874 0.5842)
					(thickness 0.1524)
				)
				(justify left)
			)
		)
		(property "Value" ""
			(at 0 0 0)
			(layer "F.Fab")
			(effects
				(font
					(size 1.27 1.27)
				)
			)
		)
		(duplicate_pad_numbers_are_jumpers no)
		(pad "J8" thru_hole circle
			(at 13.999972 10.999978 180)
			(size 0.906272 0.906272)
			(drill 0.499872)
			(layers "*.Cu" "*.Mask")
			(remove_unused_layers no)
			(net "GND")
			(clearance 0.0508)
			(thermal_gap 0.0508)
		)
		(pad "K1" thru_hole circle
			(at 0 11.999976 180)
			(size 0.906272 0.906272)
			(drill 0.499872)
			(layers "*.Cu" "*.Mask")
			(remove_unused_layers no)
			(net "GND")
			(clearance 0.0508)
			(thermal_gap 0.0508)
		)
		(pad "K3" thru_hole circle
			(at 3.999992 11.999976 180)
			(size 0.906272 0.906272)
			(drill 0.499872)
			(layers "*.Cu" "*.Mask")
			(remove_unused_layers no)
			(net "GND")
			(clearance 0.0508)
			(thermal_gap 0.0508)
		)
		(pad "K5" thru_hole circle
			(at 7.999984 11.999976 180)
			(size 0.906272 0.906272)
			(drill 0.499872)
			(layers "*.Cu" "*.Mask")
			(remove_unused_layers no)
			(net "GND")
			(clearance 0.0508)
			(thermal_gap 0.0508)
		)
		(pad "K7" thru_hole circle
			(at 11.999976 11.999976 180)
			(size 0.906272 0.906272)
			(drill 0.499872)
			(layers "*.Cu" "*.Mask")
			(remove_unused_layers no)
			(net "GND")
			(clearance 0.0508)
			(thermal_gap 0.0508)
		)
		(pad "M2" thru_hole circle
			(at 1.999996 14.59992 180)
			(size 0.906272 0.906272)
			(drill 0.499872)
			(layers "*.Cu" "*.Mask")
			(remove_unused_layers no)
			(net "GND")
			(clearance 0.0508)
			(thermal_gap 0.0508)
		)
		(pad "M4" thru_hole circle
			(at 5.999988 14.59992 180)
			(size 0.906272 0.906272)
			(drill 0.499872)
			(layers "*.Cu" "*.Mask")
			(remove_unused_layers no)
			(net "GND")
			(clearance 0.0508)
			(thermal_gap 0.0508)
		)
		(pad "M6" thru_hole circle
			(at 9.99998 14.59992 180)
			(size 0.906272 0.906272)
			(drill 0.499872)
			(layers "*.Cu" "*.Mask")
			(remove_unused_layers no)
			(net "GND")
			(clearance 0.0508)
			(thermal_gap 0.0508)
		)
		(pad "M8" thru_hole circle
			(at 13.999972 14.59992 180)
			(size 0.906272 0.906272)
			(drill 0.499872)
			(layers "*.Cu" "*.Mask")
			(remove_unused_layers no)
			(net "GND")
			(clearance 0.0508)
			(thermal_gap 0.0508)
		)
		(pad "N1" thru_hole circle
			(at 0 15.599918 180)
			(size 0.906272 0.906272)
			(drill 0.499872)
			(layers "*.Cu" "*.Mask")
			(remove_unused_layers no)
			(net "GND")
			(clearance 0.0508)
			(thermal_gap 0.0508)
		)
		(pad "N2" thru_hole circle
			(at 1.999996 15.80007 180)
			(size 0.766318 0.766318)
			(drill 0.359918)
			(layers "*.Cu" "*.Mask")
			(remove_unused_layers no)
			(net "NC_J112_N2")
			(clearance 0.0508)
			(thermal_gap 0.0508)
		)
		(pad "N3" thru_hole circle
			(at 3.999992 15.599918 180)
			(size 0.906272 0.906272)
			(drill 0.499872)
			(layers "*.Cu" "*.Mask")
			(remove_unused_layers no)
			(net "GND")
			(clearance 0.0508)
			(thermal_gap 0.0508)
		)
		(pad "N5" thru_hole circle
			(at 7.999984 15.599918 180)
			(size 0.906272 0.906272)
			(drill 0.499872)
			(layers "*.Cu" "*.Mask")
			(remove_unused_layers no)
			(net "GND")
			(clearance 0.0508)
			(thermal_gap 0.0508)
		)
		(pad "N7" thru_hole circle
			(at 11.999976 15.599918 180)
			(size 0.906272 0.906272)
			(drill 0.499872)
			(layers "*.Cu" "*.Mask")
			(remove_unused_layers no)
			(net "GND")
			(clearance 0.0508)
			(thermal_gap 0.0508)
		)
		(pad "O2" thru_hole circle
			(at 1.999996 16.999966 180)
			(size 0.766318 0.766318)
			(drill 0.359918)
			(layers "*.Cu" "*.Mask")
			(remove_unused_layers no)
			(net "NC_J112_O2")
			(clearance 0.0508)
			(thermal_gap 0.0508)
		)
		(pad "O5" thru_hole circle
			(at 7.999984 16.800068 180)
			(size 0.766318 0.766318)
			(drill 0.359918)
			(layers "*.Cu" "*.Mask")
			(remove_unused_layers no)
			(net "NC_J112_O5")
			(clearance 0.0508)
			(thermal_gap 0.0508)
		)
		(pad "P2" thru_hole circle
			(at 1.999996 18.200116 180)
			(size 0.906272 0.906272)
			(drill 0.499872)
			(layers "*.Cu" "*.Mask")
			(remove_unused_layers no)
			(net "GND")
			(clearance 0.0508)
			(thermal_gap 0.0508)
		)
		(pad "P4" thru_hole circle
			(at 5.999988 18.200116 180)
			(size 0.906272 0.906272)
			(drill 0.499872)
			(layers "*.Cu" "*.Mask")
			(remove_unused_layers no)
			(net "GND")
			(clearance 0.0508)
			(thermal_gap 0.0508)
		)
		(pad "P5" thru_hole circle
			(at 7.999984 17.999964 180)
			(size 0.766318 0.766318)
			(drill 0.359918)
			(layers "*.Cu" "*.Mask")
			(remove_unused_layers no)
			(net "NC_J112_P5")
			(clearance 0.0508)
			(thermal_gap 0.0508)
		)
		(pad "P6" thru_hole circle
			(at 9.99998 18.200116 180)
			(size 0.906272 0.906272)
			(drill 0.499872)
			(layers "*.Cu" "*.Mask")
			(remove_unused_layers no)
			(net "GND")
			(clearance 0.0508)
			(thermal_gap 0.0508)
		)
		(pad "P8" thru_hole circle
			(at 13.999972 18.200116 180)
			(size 0.906272 0.906272)
			(drill 0.499872)
			(layers "*.Cu" "*.Mask")
			(remove_unused_layers no)
			(net "GND")
			(clearance 0.0508)
			(thermal_gap 0.0508)
		)
		(pad "Q1" thru_hole circle
			(at 0 19.200114 180)
			(size 0.906272 0.906272)
			(drill 0.499872)
			(layers "*.Cu" "*.Mask")
			(remove_unused_layers no)
			(net "GND")
			(clearance 0.0508)
			(thermal_gap 0.0508)
		)
		(pad "Q3" thru_hole circle
			(at 3.999992 19.200114 180)
			(size 0.906272 0.906272)
			(drill 0.499872)
			(layers "*.Cu" "*.Mask")
			(remove_unused_layers no)
			(net "GND")
			(clearance 0.0508)
			(thermal_gap 0.0508)
		)
		(pad "Q4" thru_hole circle
			(at 5.999988 19.400012 180)
			(size 0.766318 0.766318)
			(drill 0.359918)
			(layers "*.Cu" "*.Mask")
			(remove_unused_layers no)
			(net "SMB_1_BMC_GPU_BUF_SCL")
			(clearance 0.0508)
			(thermal_gap 0.0508)
		)
		(pad "Q5" thru_hole circle
			(at 7.999984 19.200114 180)
			(size 0.906272 0.906272)
			(drill 0.499872)
			(layers "*.Cu" "*.Mask")
			(remove_unused_layers no)
			(net "GND")
			(clearance 0.0508)
			(thermal_gap 0.0508)
		)
		(pad "Q7" thru_hole circle
			(at 11.999976 19.200114 180)
			(size 0.906272 0.906272)
			(drill 0.499872)
			(layers "*.Cu" "*.Mask")
			(remove_unused_layers no)
			(net "GND")
			(clearance 0.0508)
			(thermal_gap 0.0508)
		)
		(pad "R3" thru_hole circle
			(at 3.999992 20.40001 180)
			(size 0.766318 0.766318)
			(drill 0.359918)
			(layers "*.Cu" "*.Mask")
			(remove_unused_layers no)
			(net "SMB_2_BMC_GPU_BUF_SCL")
			(clearance 0.0508)
			(thermal_gap 0.0508)
		)
		(pad "R4" thru_hole circle
			(at 5.999988 20.599908 180)
			(size 0.766318 0.766318)
			(drill 0.359918)
			(layers "*.Cu" "*.Mask")
			(remove_unused_layers no)
			(net "SMB_1_BMC_GPU_BUF_SDA")
			(clearance 0.0508)
			(thermal_gap 0.0508)
		)
		(pad "R5" thru_hole circle
			(at 7.999984 20.40001 180)
			(size 0.766318 0.766318)
			(drill 0.359918)
			(layers "*.Cu" "*.Mask")
			(remove_unused_layers no)
			(net "NC_J112_R5")
			(clearance 0.0508)
			(thermal_gap 0.0508)
		)
		(pad "S2" thru_hole circle
			(at 1.999996 21.800058 180)
			(size 0.906272 0.906272)
			(drill 0.499872)
			(layers "*.Cu" "*.Mask")
			(remove_unused_layers no)
			(net "GND")
			(clearance 0.0508)
			(thermal_gap 0.0508)
		)
		(pad "S3" thru_hole circle
			(at 3.999992 21.599906 180)
			(size 0.766318 0.766318)
			(drill 0.359918)
			(layers "*.Cu" "*.Mask")
			(remove_unused_layers no)
			(net "SMB_2_BMC_GPU_BUF_SDA")
			(clearance 0.0508)
			(thermal_gap 0.0508)
		)
	)
)
